# T6G (Grand Teton) — schematic netlist excerpt (pin names and nets, part order shuffled) for the footprints in the layout excerpt that follows; sources: Cadence DE-HDL packaged netlist, KiCad conversion of 04192023_DAF0TMB3IC0_F0TG_MB_C_brd_V02_OCP.brd

R3794  Q_RES  0 5% EMPTY  pkg 0402LF  page 134 : A = P3V3_OCP_PWRGD_1 ; B = OCP_V3_1_P3V3_PWRGD
R174  Q_RES  33 5% CHIP  pkg 0402LF  page 81 : A = SCM_IRQ_1V8_R_N ; B = SCM_IRQ_1V8_N

(kicad_pcb
	(version 20260206)
	(generator "pcbnew")
	(generator_version "10.0")
	(general
		(thickness 1.6)
		(legacy_teardrops no)
	)
	(paper "A4")
	(title_block
		(title "04192023_DAF0TMB3IC0_F0TG_MB_C_brd_V02_OCP.brd")
		(comment 1 "Grand Teton / footprints 4621-4622 of 8354")
	)
	(layers
		(0 "F.Cu" signal "TOP")
		(4 "In1.Cu" signal "GND")
		(6 "In2.Cu" signal "IN1")
		(8 "In3.Cu" signal "GND1")
		(10 "In4.Cu" signal "IN2")
		(12 "In5.Cu" signal "GND2")
		(14 "In6.Cu" signal "IN3")
		(16 "In7.Cu" signal "GND3")
		(18 "In8.Cu" signal "VCC")
		(20 "In9.Cu" signal "VCC1")
		(22 "In10.Cu" signal "GND4")
		(24 "In11.Cu" signal "IN4")
		(26 "In12.Cu" signal "GND5")
		(28 "In13.Cu" signal "IN5")
		(30 "In14.Cu" signal "GND6")
		(32 "In15.Cu" signal "IN6")
		(34 "In16.Cu" signal "GND7")
		(2 "B.Cu" signal "BOTTOM")
		(9 "F.Adhes" user "F.Adhesive")
		(11 "B.Adhes" user "B.Adhesive")
		(13 "F.Paste" user "Package Geometry/Pastemask Top")
		(15 "B.Paste" user "Package Geometry/Pastemask Bottom")
		(5 "F.SilkS" user "Ref Des/Silkscreen Top")
		(7 "B.SilkS" user "Ref Des/Silkscreen Bottom")
		(1 "F.Mask" user "Board Geometry/Soldermask Top")
		(3 "B.Mask" user "Board Geometry/Soldermask Bottom")
		(17 "Dwgs.User" user "User.Drawings")
		(19 "Cmts.User" user "User.Comments")
		(21 "Eco1.User" user "User.Eco1")
		(23 "Eco2.User" user "User.Eco2")
		(25 "Edge.Cuts" user "Board Geometry/Outline")
		(27 "Margin" user)
		(31 "F.CrtYd" user "Package Geometry/Place Bound Top")
		(29 "B.CrtYd" user "Package Geometry/Place Bound Bottom")
		(35 "F.Fab" user "Ref Des/Assembly Top")
		(33 "B.Fab" user "Ref Des/Assembly Bottom")
	)
	(footprint ""
		(layer "F.Cu")
		(at 428.880016 -102.37724 -90)
		(property "Reference" "R3794"
			(at 0 0 270)
			(layer "F.SilkS")
			(hide yes)
			(effects
				(font
					(size 1.27 1.27)
				)
			)
		)
		(property "Value" ""
			(at 0 0 270)
			(layer "F.Fab")
			(effects
				(font
					(size 1.27 1.27)
				)
			)
		)
		(duplicate_pad_numbers_are_jumpers no)
		(fp_line
			(start -0.7874 0.4064)
			(end -0.7874 -0.4064)
			(stroke
				(width 0.1524)
				(type default)
			)
			(layer "F.SilkS")
		)
		(fp_line
			(start 0.7874 0.4064)
			(end -0.7874 0.4064)
			(stroke
				(width 0.1524)
				(type default)
			)
			(layer "F.SilkS")
		)
		(fp_line
			(start -0.7874 -0.4064)
			(end 0.7874 -0.4064)
			(stroke
				(width 0.1524)
				(type default)
			)
			(layer "F.SilkS")
		)
		(fp_line
			(start 0.7874 -0.4064)
			(end 0.7874 0.4064)
			(stroke
				(width 0.1524)
				(type default)
			)
			(layer "F.SilkS")
		)
		(fp_line
			(start -0.67945 0.3048)
			(end -0.67945 -0.305054)
			(stroke
				(width 0.1)
				(type default)
			)
			(layer "F.Fab")
		)
		(fp_line
			(start -0.12065 0.3048)
			(end -0.67945 0.3048)
			(stroke
				(width 0.1)
				(type default)
			)
			(layer "F.Fab")
		)
		(fp_line
			(start 0.120396 0.3048)
			(end 0.120396 0.2794)
			(stroke
				(width 0.1)
				(type default)
			)
			(layer "F.Fab")
		)
		(fp_line
			(start 0.67945 0.3048)
			(end 0.120396 0.3048)
			(stroke
				(width 0.1)
				(type default)
			)
			(layer "F.Fab")
		)
		(fp_line
			(start -0.12065 0.2794)
			(end -0.12065 0.3048)
			(stroke
				(width 0.1)
				(type default)
			)
			(layer "F.Fab")
		)
		(fp_line
			(start 0.120396 0.2794)
			(end -0.12065 0.2794)
			(stroke
				(width 0.1)
				(type default)
			)
			(layer "F.Fab")
		)
		(fp_line
			(start -0.12065 -0.2794)
			(end 0.12065 -0.2794)
			(stroke
				(width 0.1)
				(type default)
			)
			(layer "F.Fab")
		)
		(fp_line
			(start 0.12065 -0.2794)
			(end 0.12065 -0.3048)
			(stroke
				(width 0.1)
				(type default)
			)
			(layer "F.Fab")
		)
		(fp_line
			(start 0.12065 -0.3048)
			(end 0.67945 -0.3048)
			(stroke
				(width 0.1)
				(type default)
			)
			(layer "F.Fab")
		)
		(fp_line
			(start 0.67945 -0.3048)
			(end 0.67945 0.3048)
			(stroke
				(width 0.1)
				(type default)
			)
			(layer "F.Fab")
		)
		(fp_line
			(start -0.67945 -0.305054)
			(end -0.12065 -0.305054)
			(stroke
				(width 0.1)
				(type default)
			)
			(layer "F.Fab")
		)
		(fp_line
			(start -0.12065 -0.305054)
			(end -0.12065 -0.2794)
			(stroke
				(width 0.1)
				(type default)
			)
			(layer "F.Fab")
		)
		(pad "1" smd circle
			(at -0.40005 0 270)
			(size 0 0)
			(layers "F.Cu" "F.Mask" "F.Paste")
			(net "P3V3_OCP_PWRGD_1")
		)
		(pad "2" smd circle
			(at 0.40005 0 270)
			(size 0 0)
			(layers "F.Cu" "F.Mask" "F.Paste")
			(net "OCP_V3_1_P3V3_PWRGD")
		)
	)
	(footprint ""
		(layer "F.Cu")
		(at 190.119 -129.377948 90)
		(property "Reference" "R174"
			(at 0 0 90)
			(layer "F.SilkS")
			(hide yes)
			(effects
				(font
					(size 1.27 1.27)
				)
			)
		)
		(property "Value" ""
			(at 0 0 90)
			(layer "F.Fab")
			(effects
				(font
					(size 1.27 1.27)
				)
			)
		)
		(duplicate_pad_numbers_are_jumpers no)
		(fp_line
			(start 0.7874 -0.4064)
			(end 0.7874 0.4064)
			(stroke
				(width 0.1524)
				(type default)
			)
			(layer "F.SilkS")
		)
		(fp_line
			(start -0.7874 -0.4064)
			(end 0.7874 -0.4064)
			(stroke
				(width 0.1524)
				(type default)
			)
			(layer "F.SilkS")
		)
		(fp_line
			(start 0.7874 0.4064)
			(end -0.7874 0.4064)
			(stroke
				(width 0.1524)
				(type default)
			)
			(layer "F.SilkS")
		)
		(fp_line
			(start -0.7874 0.4064)
			(end -0.7874 -0.4064)
			(stroke
				(width 0.1524)
				(type default)
			)
			(layer "F.SilkS")
		)
		(fp_line
			(start -0.12065 -0.305054)
			(end -0.12065 -0.2794)
			(stroke
				(width 0.1)
				(type default)
			)
			(layer "F.Fab")
		)
		(fp_line
			(start -0.67945 -0.305054)
			(end -0.12065 -0.305054)
			(stroke
				(width 0.1)
				(type default)
			)
			(layer "F.Fab")
		)
		(fp_line
			(start 0.67945 -0.3048)
			(end 0.67945 0.3048)
			(stroke
				(width 0.1)
				(type default)
			)
			(layer "F.Fab")
		)
		(fp_line
			(start 0.12065 -0.3048)
			(end 0.67945 -0.3048)
			(stroke
				(width 0.1)
				(type default)
			)
			(layer "F.Fab")
		)
		(fp_line
			(start 0.12065 -0.2794)
			(end 0.12065 -0.3048)
			(stroke
				(width 0.1)
				(type default)
			)
			(layer "F.Fab")
		)
		(fp_line
			(start -0.12065 -0.2794)
			(end 0.12065 -0.2794)
			(stroke
				(width 0.1)
				(type default)
			)
			(layer "F.Fab")
		)
		(fp_line
			(start 0.120396 0.2794)
			(end -0.12065 0.2794)
			(stroke
				(width 0.1)
				(type default)
			)
			(layer "F.Fab")
		)
		(fp_line
			(start -0.12065 0.2794)
			(end -0.12065 0.3048)
			(stroke
				(width 0.1)
				(type default)
			)
			(layer "F.Fab")
		)
		(fp_line
			(start 0.67945 0.3048)
			(end 0.120396 0.3048)
			(stroke
				(width 0.1)
				(type default)
			)
			(layer "F.Fab")
		)
		(fp_line
			(start 0.120396 0.3048)
			(end 0.120396 0.2794)
			(stroke
				(width 0.1)
				(type default)
			)
			(layer "F.Fab")
		)
		(fp_line
			(start -0.12065 0.3048)
			(end -0.67945 0.3048)
			(stroke
				(width 0.1)
				(type default)
			)
			(layer "F.Fab")
		)
		(fp_line
			(start -0.67945 0.3048)
			(end -0.67945 -0.305054)
			(stroke
				(width 0.1)
				(type default)
			)
			(layer "F.Fab")
		)
		(pad "1" smd circle
			(at -0.40005 0 90)
			(size 0 0)
			(layers "F.Cu" "F.Mask" "F.Paste")
			(net "SCM_IRQ_1V8_R_N")
		)
		(pad "2" smd circle
			(at 0.40005 0 90)
			(size 0 0)
			(layers "F.Cu" "F.Mask" "F.Paste")
			(net "SCM_IRQ_1V8_N")
		)
	)
)
